(kicad_pcb
	(version 20260206)
	(generator "pcbnew")
	(generator_version "10.0")
	(general
		(thickness 1.6)
		(legacy_teardrops no)
	)
	(paper "A4")
	(title_block
		(title "Bryce Canyon_F.DPB_16315-1-OCP.brd")
		(comment 1 "Bryce Canyon / footprints 684-689 of 2223")
	)
	(layers
		(0 "F.Cu" signal "TOP")
		(4 "In1.Cu" signal "L2GND")
		(6 "In2.Cu" signal "L3")
		(8 "In3.Cu" signal "L4GND")
		(10 "In4.Cu" signal "L5")
		(12 "In5.Cu" signal "L6VCC")
		(14 "In6.Cu" signal "L7VCC")
		(16 "In7.Cu" signal "L8")
		(18 "In8.Cu" signal "L9GND")
		(20 "In9.Cu" signal "L10")
		(22 "In10.Cu" signal "L11GND")
		(2 "B.Cu" signal "BOTTOM")
		(9 "F.Adhes" user "F.Adhesive")
		(11 "B.Adhes" user "B.Adhesive")
		(13 "F.Paste" user "Package Geometry/Pastemask Top")
		(15 "B.Paste" user "Package Geometry/Pastemask Bottom")
		(5 "F.SilkS" user "Ref Des/Silkscreen Top")
		(7 "B.SilkS" user "Ref Des/Silkscreen Bottom")
		(1 "F.Mask" user "Board Geometry/Soldermask Top")
		(3 "B.Mask" user "Board Geometry/Soldermask Bottom")
		(17 "Dwgs.User" user "User.Drawings")
		(19 "Cmts.User" user "User.Comments")
		(21 "Eco1.User" user "User.Eco1")
		(23 "Eco2.User" user "User.Eco2")
		(25 "Edge.Cuts" user "Board Geometry/Outline")
		(27 "Margin" user)
		(31 "F.CrtYd" user "Package Geometry/Place Bound Top")
		(29 "B.CrtYd" user "Package Geometry/Place Bound Bottom")
		(35 "F.Fab" user "Ref Des/Assembly Top")
		(33 "B.Fab" user "Ref Des/Assembly Bottom")
	)
	(footprint ""
		(layer "F.Cu")
		(at 349.812102 -292.169342 90)
		(property "Reference" "R291"
			(at 0 0 90)
			(layer "F.SilkS")
			(hide yes)
			(effects
				(font
					(size 1.27 1.27)
				)
			)
		)
		(property "Value" "10KR2F-2-GP"
			(at 0.064008 -3.993896 90)
			(unlocked yes)
			(layer "F.Fab")
			(hide yes)
			(effects
				(font
					(size 1.016 1.016)
					(thickness 0.1524)
				)
			)
		)
		(property "Device Type" "R402H16"
			(at 0.064008 -5.517896 90)
			(unlocked yes)
			(layer "F.Fab")
			(hide yes)
			(effects
				(font
					(size 1.016 1.016)
					(thickness 0.1524)
				)
			)
		)
		(duplicate_pad_numbers_are_jumpers no)
		(fp_line
			(start 0.508 -0.9398)
			(end -0.508 -0.9398)
			(stroke
				(width 0.1524)
				(type default)
			)
			(layer "F.SilkS")
		)
		(fp_line
			(start -0.508 -0.9398)
			(end -0.508 0.9398)
			(stroke
				(width 0.1524)
				(type default)
			)
			(layer "F.SilkS")
		)
		(fp_rect
			(start -0.508 0.9398)
			(end 0.508 -0.9398)
			(stroke
				(width 0)
				(type default)
			)
			(fill no)
			(layer "F.CrtYd")
		)
		(fp_rect
			(start -0.508 0.9398)
			(end 0.508 -0.9398)
			(stroke
				(width 0)
				(type default)
			)
			(fill no)
			(layer "F.Fab")
		)
		(pad "1" smd custom
			(at 0 -0.4445 90)
			(size 0.1397 0.1397)
			(layers "F.Cu" "F.Mask" "F.Paste")
			(net "P3V3_STBY_A")
			(options
				(clearance outline)
				(anchor circle)
			)
			(primitives
				(gr_poly
					(pts
						(arc
							(start -0.1778 -0.2794)
							(mid -0.249642 -0.249642)
							(end -0.2794 -0.1778)
						)
						(arc
							(start -0.2794 0.1778)
							(mid -0.249642 0.249642)
							(end -0.1778 0.2794)
						)
						(arc
							(start 0.1778 0.2794)
							(mid 0.249642 0.249642)
							(end 0.2794 0.1778)
						)
						(arc
							(start 0.2794 -0.1778)
							(mid 0.249642 -0.249642)
							(end 0.1778 -0.2794)
						)
					)
					(width 0)
					(fill yes)
				)
			)
		)
		(pad "2" smd custom
			(at 0 0.4445 90)
			(size 0.1397 0.1397)
			(layers "F.Cu" "F.Mask" "F.Paste")
			(net "HDD_PRSNT_7")
			(options
				(clearance outline)
				(anchor circle)
			)
			(primitives
				(gr_poly
					(pts
						(arc
							(start -0.1778 -0.2794)
							(mid -0.249642 -0.249642)
							(end -0.2794 -0.1778)
						)
						(arc
							(start -0.2794 0.1778)
							(mid -0.249642 0.249642)
							(end -0.1778 0.2794)
						)
						(arc
							(start 0.1778 0.2794)
							(mid 0.249642 0.249642)
							(end 0.2794 0.1778)
						)
						(arc
							(start 0.2794 -0.1778)
							(mid 0.249642 -0.249642)
							(end 0.1778 -0.2794)
						)
					)
					(width 0)
					(fill yes)
				)
			)
		)
	)
	(footprint ""
		(layer "F.Cu")
		(at 371.557042 -242.788694 180)
		(property "Reference" "Q271"
			(at 0 0 180)
			(layer "F.SilkS")
			(hide yes)
			(effects
				(font
					(size 1.27 1.27)
				)
			)
		)
		(property "Value" "SSM3K324R-GP"
			(at 0.127 -8.9662 180)
			(unlocked yes)
			(layer "F.Fab")
			(hide yes)
			(effects
				(font
					(size 1.016 1.016)
					(thickness 0.1524)
				)
			)
		)
		(property "Device Type" "SOT23DGS2D4H35"
			(at 0.127 -10.4902 180)
			(unlocked yes)
			(layer "F.Fab")
			(hide yes)
			(effects
				(font
					(size 1.016 1.016)
					(thickness 0.1524)
				)
			)
		)
		(duplicate_pad_numbers_are_jumpers no)
		(fp_line
			(start 1.651 1.778)
			(end 1.651 -1.778)
			(stroke
				(width 0.1524)
				(type default)
			)
			(layer "F.SilkS")
		)
		(fp_line
			(start 1.651 -1.778)
			(end -1.651 -1.778)
			(stroke
				(width 0.1524)
				(type default)
			)
			(layer "F.SilkS")
		)
		(fp_line
			(start -1.651 1.778)
			(end 1.651 1.778)
			(stroke
				(width 0.1524)
				(type default)
			)
			(layer "F.SilkS")
		)
		(fp_line
			(start -1.651 -1.778)
			(end -1.651 1.778)
			(stroke
				(width 0.1524)
				(type default)
			)
			(layer "F.SilkS")
		)
		(fp_poly
			(pts
				(xy -1.778 1.8796) (xy -1.778 -1.8796) (xy 1.778 -1.8796) (xy 1.778 1.8796)
			)
			(stroke
				(width 0)
				(type default)
			)
			(fill no)
			(layer "F.CrtYd")
		)
		(fp_poly
			(pts
				(xy -1.778 1.8796) (xy -1.778 -1.8796) (xy 1.778 -1.8796) (xy 1.778 1.8796)
			)
			(stroke
				(width 0)
				(type default)
			)
			(fill no)
			(layer "F.Fab")
		)
		(pad "D" smd custom
			(at 0 -0.9525 180)
			(size 0.1905 0.1905)
			(layers "F.Cu" "F.Mask" "F.Paste")
			(net "DRV_ACT_8_N")
			(options
				(clearance outline)
				(anchor circle)
			)
			(primitives
				(gr_poly
					(pts
						(arc
							(start -0.1778 0.5715)
							(mid -0.321484 0.511984)
							(end -0.381 0.3683)
						)
						(arc
							(start -0.381 -0.3683)
							(mid -0.321484 -0.511984)
							(end -0.1778 -0.5715)
						)
						(arc
							(start 0.1778 -0.5715)
							(mid 0.321484 -0.511984)
							(end 0.381 -0.3683)
						)
						(arc
							(start 0.381 0.3683)
							(mid 0.321484 0.511984)
							(end 0.1778 0.5715)
						)
					)
					(width 0)
					(fill yes)
				)
			)
		)
		(pad "G" smd custom
			(at -0.98425 0.9525 180)
			(size 0.1905 0.1905)
			(layers "F.Cu" "F.Mask" "F.Paste")
			(net "DRIVE_A_8_ACT")
			(options
				(clearance outline)
				(anchor circle)
			)
			(primitives
				(gr_poly
					(pts
						(arc
							(start -0.1778 0.5715)
							(mid -0.321484 0.511984)
							(end -0.381 0.3683)
						)
						(arc
							(start -0.381 -0.3683)
							(mid -0.321484 -0.511984)
							(end -0.1778 -0.5715)
						)
						(arc
							(start 0.1778 -0.5715)
							(mid 0.321484 -0.511984)
							(end 0.381 -0.3683)
						)
						(arc
							(start 0.381 0.3683)
							(mid 0.321484 0.511984)
							(end 0.1778 0.5715)
						)
					)
					(width 0)
					(fill yes)
				)
			)
		)
		(pad "S" smd custom
			(at 0.98425 0.9525 180)
			(size 0.1905 0.1905)
			(layers "F.Cu" "F.Mask" "F.Paste")
			(net "GND")
			(options
				(clearance outline)
				(anchor circle)
			)
			(primitives
				(gr_poly
					(pts
						(arc
							(start -0.1778 0.5715)
							(mid -0.321484 0.511984)
							(end -0.381 0.3683)
						)
						(arc
							(start -0.381 -0.3683)
							(mid -0.321484 -0.511984)
							(end -0.1778 -0.5715)
						)
						(arc
							(start 0.1778 -0.5715)
							(mid 0.321484 -0.511984)
							(end 0.381 -0.3683)
						)
						(arc
							(start 0.381 0.3683)
							(mid 0.321484 0.511984)
							(end 0.1778 0.5715)
						)
					)
					(width 0)
					(fill yes)
				)
			)
		)
	)
	(footprint ""
		(layer "F.Cu")
		(at 223.421448 -350.624648 -90)
		(property "Reference" "R22"
			(at 0 0 270)
			(layer "F.SilkS")
			(hide yes)
			(effects
				(font
					(size 1.27 1.27)
				)
			)
		)
		(property "Value" "0R2J-2-GP"
			(at 0.064008 -3.993896 270)
			(unlocked yes)
			(layer "F.Fab")
			(hide yes)
			(effects
				(font
					(size 1.016 1.016)
					(thickness 0.1524)
				)
			)
		)
		(property "Device Type" "R402H16"
			(at 0.064008 -5.517896 270)
			(unlocked yes)
			(layer "F.Fab")
			(hide yes)
			(effects
				(font
					(size 1.016 1.016)
					(thickness 0.1524)
				)
			)
		)
		(duplicate_pad_numbers_are_jumpers no)
		(fp_line
			(start -0.508 -0.9398)
			(end -0.508 0.9398)
			(stroke
				(width 0.1524)
				(type default)
			)
			(layer "F.SilkS")
		)
		(fp_line
			(start 0.508 -0.9398)
			(end -0.508 -0.9398)
			(stroke
				(width 0.1524)
				(type default)
			)
			(layer "F.SilkS")
		)
		(fp_rect
			(start -0.508 0.9398)
			(end 0.508 -0.9398)
			(stroke
				(width 0)
				(type default)
			)
			(fill no)
			(layer "F.CrtYd")
		)
		(fp_rect
			(start -0.508 0.9398)
			(end 0.508 -0.9398)
			(stroke
				(width 0)
				(type default)
			)
			(fill no)
			(layer "F.Fab")
		)
		(pad "1" smd custom
			(at 0 -0.4445 270)
			(size 0.1397 0.1397)
			(layers "F.Cu" "F.Mask" "F.Paste")
			(net "VOL_SEN_SDA")
			(options
				(clearance outline)
				(anchor circle)
			)
			(primitives
				(gr_poly
					(pts
						(arc
							(start -0.1778 -0.2794)
							(mid -0.249642 -0.249642)
							(end -0.2794 -0.1778)
						)
						(arc
							(start -0.2794 0.1778)
							(mid -0.249642 0.249642)
							(end -0.1778 0.2794)
						)
						(arc
							(start 0.1778 0.2794)
							(mid 0.249642 0.249642)
							(end 0.2794 0.1778)
						)
						(arc
							(start 0.2794 -0.1778)
							(mid 0.249642 -0.249642)
							(end 0.1778 -0.2794)
						)
					)
					(width 0)
					(fill yes)
				)
			)
		)
		(pad "2" smd custom
			(at 0 0.4445 270)
			(size 0.1397 0.1397)
			(layers "F.Cu" "F.Mask" "F.Paste")
			(net "I2C_DPB_A_SDA_BUF")
			(options
				(clearance outline)
				(anchor circle)
			)
			(primitives
				(gr_poly
					(pts
						(arc
							(start -0.1778 -0.2794)
							(mid -0.249642 -0.249642)
							(end -0.2794 -0.1778)
						)
						(arc
							(start -0.2794 0.1778)
							(mid -0.249642 0.249642)
							(end -0.1778 0.2794)
						)
						(arc
							(start 0.1778 0.2794)
							(mid 0.249642 0.249642)
							(end 0.2794 0.1778)
						)
						(arc
							(start 0.2794 -0.1778)
							(mid 0.249642 -0.249642)
							(end 0.1778 -0.2794)
						)
					)
					(width 0)
					(fill yes)
				)
			)
		)
	)
	(footprint ""
		(layer "F.Cu")
		(at 370.6368 -145.8214 180)
		(property "Reference" "C558"
			(at 0 0 180)
			(layer "F.SilkS")
			(hide yes)
			(effects
				(font
					(size 1.27 1.27)
				)
			)
		)
		(property "Value" "SCD1U16V2KX-3GP"
			(at 1.1811 -2.7051 180)
			(unlocked yes)
			(layer "F.Fab")
			(hide yes)
			(effects
				(font
					(size 1.016 1.016)
					(thickness 0.1524)
				)
			)
		)
		(property "Device Type" "C402H22"
			(at 1.1811 -4.2291 180)
			(unlocked yes)
			(layer "F.Fab")
			(hide yes)
			(effects
				(font
					(size 1.016 1.016)
					(thickness 0.1524)
				)
			)
		)
		(duplicate_pad_numbers_are_jumpers no)
		(fp_rect
			(start -0.4318 0.9525)
			(end 0.4318 -0.9525)
			(stroke
				(width 0)
				(type default)
			)
			(fill no)
			(layer "F.CrtYd")
		)
		(fp_rect
			(start -0.4318 0.9525)
			(end 0.4318 -0.9525)
			(stroke
				(width 0)
				(type default)
			)
			(fill no)
			(layer "F.Fab")
		)
		(pad "1" smd custom
			(at 0 -0.4445 180)
			(size 0.1524 0.1524)
			(layers "F.Cu" "F.Mask" "F.Paste")
			(net "MB1_CM_VOUT_R")
			(options
				(clearance outline)
				(anchor circle)
			)
			(primitives
				(gr_poly
					(pts
						(arc
							(start 0.3048 -0.2032)
							(mid 0.275042 -0.275042)
							(end 0.2032 -0.3048)
						)
						(arc
							(start -0.2032 -0.3048)
							(mid -0.275042 -0.275042)
							(end -0.3048 -0.2032)
						)
						(arc
							(start -0.3048 0.2032)
							(mid -0.275042 0.275042)
							(end -0.2032 0.3048)
						)
						(arc
							(start 0.2032 0.3048)
							(mid 0.275042 0.275042)
							(end 0.3048 0.2032)
						)
					)
					(width 0)
					(fill yes)
				)
			)
		)
		(pad "2" smd custom
			(at 0 0.4445 180)
			(size 0.1524 0.1524)
			(layers "F.Cu" "F.Mask" "F.Paste")
			(net "AGND_CURRENT_MONOB")
			(options
				(clearance outline)
				(anchor circle)
			)
			(primitives
				(gr_poly
					(pts
						(arc
							(start 0.3048 -0.2032)
							(mid 0.275042 -0.275042)
							(end 0.2032 -0.3048)
						)
						(arc
							(start -0.2032 -0.3048)
							(mid -0.275042 -0.275042)
							(end -0.3048 -0.2032)
						)
						(arc
							(start -0.3048 0.2032)
							(mid -0.275042 0.275042)
							(end -0.2032 0.3048)
						)
						(arc
							(start 0.2032 0.3048)
							(mid 0.275042 0.275042)
							(end 0.3048 0.2032)
						)
					)
					(width 0)
					(fill yes)
				)
			)
		)
	)
	(footprint ""
		(layer "F.Cu")
		(at 113.150396 -45.633894)
		(property "Reference" "R768"
			(at 0 0 0)
			(layer "F.SilkS")
			(hide yes)
			(effects
				(font
					(size 1.27 1.27)
				)
			)
		)
		(property "Value" "0R2J-2-GP"
			(at 0.064008 -3.993896 0)
			(unlocked yes)
			(layer "F.Fab")
			(hide yes)
			(effects
				(font
					(size 1.016 1.016)
					(thickness 0.1524)
				)
			)
		)
		(property "Device Type" "R402H16"
			(at 0.064008 -5.517896 0)
			(unlocked yes)
			(layer "F.Fab")
			(hide yes)
			(effects
				(font
					(size 1.016 1.016)
					(thickness 0.1524)
				)
			)
		)
		(duplicate_pad_numbers_are_jumpers no)
		(fp_line
			(start -0.508 -0.9398)
			(end -0.508 0.9398)
			(stroke
				(width 0.1524)
				(type default)
			)
			(layer "F.SilkS")
		)
		(fp_line
			(start 0.508 -0.9398)
			(end -0.508 -0.9398)
			(stroke
				(width 0.1524)
				(type default)
			)
			(layer "F.SilkS")
		)
		(fp_rect
			(start -0.508 0.9398)
			(end 0.508 -0.9398)
			(stroke
				(width 0)
				(type default)
			)
			(fill no)
			(layer "F.CrtYd")
		)
		(fp_rect
			(start -0.508 0.9398)
			(end 0.508 -0.9398)
			(stroke
				(width 0)
				(type default)
			)
			(fill no)
			(layer "F.Fab")
		)
		(pad "1" smd custom
			(at 0 -0.4445)
			(size 0.1397 0.1397)
			(layers "F.Cu" "F.Mask" "F.Paste")
			(net "SW_HDD_G27")
			(options
				(clearance outline)
				(anchor circle)
			)
			(primitives
				(gr_poly
					(pts
						(arc
							(start -0.1778 -0.2794)
							(mid -0.249642 -0.249642)
							(end -0.2794 -0.1778)
						)
						(arc
							(start -0.2794 0.1778)
							(mid -0.249642 0.249642)
							(end -0.1778 0.2794)
						)
						(arc
							(start 0.1778 0.2794)
							(mid 0.249642 0.249642)
							(end 0.2794 0.1778)
						)
						(arc
							(start 0.2794 -0.1778)
							(mid 0.249642 -0.249642)
							(end 0.1778 -0.2794)
						)
					)
					(width 0)
					(fill yes)
				)
			)
		)
		(pad "2" smd custom
			(at 0 0.4445)
			(size 0.1397 0.1397)
			(layers "F.Cu" "F.Mask" "F.Paste")
			(net "SW_HDD_R27")
			(options
				(clearance outline)
				(anchor circle)
			)
			(primitives
				(gr_poly
					(pts
						(arc
							(start -0.1778 -0.2794)
							(mid -0.249642 -0.249642)
							(end -0.2794 -0.1778)
						)
						(arc
							(start -0.2794 0.1778)
							(mid -0.249642 0.249642)
							(end -0.1778 0.2794)
						)
						(arc
							(start 0.1778 0.2794)
							(mid 0.249642 0.249642)
							(end 0.2794 0.1778)
						)
						(arc
							(start 0.2794 -0.1778)
							(mid 0.249642 -0.249642)
							(end 0.1778 -0.2794)
						)
					)
					(width 0)
					(fill yes)
				)
			)
		)
	)
	(footprint ""
		(layer "F.Cu")
		(at 178.435 -285.285942 180)
		(property "Reference" "Q30"
			(at 0 0 180)
			(layer "F.SilkS")
			(hide yes)
			(effects
				(font
					(size 1.27 1.27)
				)
			)
		)
		(property "Value" "AO4406AL-GP"
			(at -3.707384 -1.5367 180)
			(unlocked yes)
			(layer "F.Fab")
			(hide yes)
			(effects
				(font
					(size 1.016 1.016)
					(thickness 0.1524)
				)
			)
		)
		(property "Device Type" "SOIC8H69"
			(at -3.707384 -3.0607 180)
			(unlocked yes)
			(layer "F.Fab")
			(hide yes)
			(effects
				(font
					(size 1.016 1.016)
					(thickness 0.1524)
				)
			)
		)
		(duplicate_pad_numbers_are_jumpers no)
		(fp_line
			(start 2.1336 1.4224)
			(end 2.1336 -1.4224)
			(stroke
				(width 0.1524)
				(type default)
			)
			(layer "F.SilkS")
		)
		(fp_line
			(start 2.1336 -1.4224)
			(end -2.7432 -1.4224)
			(stroke
				(width 0.1524)
				(type default)
			)
			(layer "F.SilkS")
		)
		(fp_line
			(start -2.1844 -0.0508)
			(end -2.7178 0.508)
			(stroke
				(width 0.1524)
				(type default)
			)
			(layer "F.SilkS")
		)
		(fp_line
			(start -2.6289 3.4417)
			(end -2.6289 1.4732)
			(stroke
				(width 0.381)
				(type default)
			)
			(layer "F.SilkS")
		)
		(fp_line
			(start -2.7178 -0.508)
			(end -2.1844 -0.0508)
			(stroke
				(width 0.1524)
				(type default)
			)
			(layer "F.SilkS")
		)
		(fp_line
			(start -2.7432 1.4224)
			(end 2.1336 1.4224)
			(stroke
				(width 0.1524)
				(type default)
			)
			(layer "F.SilkS")
		)
		(fp_line
			(start -2.7432 1.4224)
			(end -2.6416 1.4224)
			(stroke
				(width 0.1524)
				(type default)
			)
			(layer "F.SilkS")
		)
		(fp_line
			(start -2.7432 -1.4224)
			(end -2.7432 1.4224)
			(stroke
				(width 0.1524)
				(type default)
			)
			(layer "F.SilkS")
		)
		(fp_poly
			(pts
				(xy -2.2098 -1.4224) (xy -2.2098 1.4224) (xy 2.2098 1.4224) (xy 2.2098 -1.4224)
			)
			(stroke
				(width 0)
				(type default)
			)
			(fill yes)
			(layer "F.SilkS")
		)
		(fp_rect
			(start -2.450084 2.999994)
			(end 2.450084 -2.999994)
			(stroke
				(width 0)
				(type default)
			)
			(fill no)
			(layer "F.CrtYd")
		)
		(fp_poly
			(pts
				(xy -2.8194 3.6322) (xy -2.8194 -3.6322) (xy 2.8194 -3.6322) (xy 2.8194 1.18364) (xy 2.450084 1.18364)
				(xy 2.450084 -2.999994) (xy -2.450084 -2.999994) (xy -2.450084 2.999994) (xy 2.450084 2.999994)
				(xy 2.450084 1.18618) (xy 2.8194 1.18618) (xy 2.8194 3.6322)
			)
			(stroke
				(width 0)
				(type default)
			)
			(fill no)
			(layer "F.CrtYd")
		)
		(fp_rect
			(start -2.8194 3.6322)
			(end 2.8194 -3.6322)
			(stroke
				(width 0)
				(type default)
			)
			(fill no)
			(layer "F.Fab")
		)
		(pad "1" smd rect
			(at -1.905 2.54 180)
			(size 0.635 1.651)
			(layers "F.Cu" "F.Mask" "F.Paste")
			(net "P5V_HDD5")
		)
		(pad "2" smd rect
			(at -0.635 2.54 180)
			(size 0.635 1.651)
			(layers "F.Cu" "F.Mask" "F.Paste")
			(net "P5V_HDD5")
		)
		(pad "3" smd rect
			(at 0.635 2.54 180)
			(size 0.635 1.651)
			(layers "F.Cu" "F.Mask" "F.Paste")
			(net "P5V_HDD5")
		)
		(pad "4" smd rect
			(at 1.905 2.54 180)
			(size 0.635 1.651)
			(layers "F.Cu" "F.Mask" "F.Paste")
			(net "SW_HDD_P5")
		)
		(pad "5" smd rect
			(at 1.905 -2.54 180)
			(size 0.635 1.651)
			(layers "F.Cu" "F.Mask" "F.Paste")
			(net "P5V_A_1")
		)
		(pad "6" smd rect
			(at 0.635 -2.54 180)
			(size 0.635 1.651)
			(layers "F.Cu" "F.Mask" "F.Paste")
			(net "P5V_A_1")
		)
		(pad "7" smd rect
			(at -0.635 -2.54 180)
			(size 0.635 1.651)
			(layers "F.Cu" "F.Mask" "F.Paste")
			(net "P5V_A_1")
		)
		(pad "8" smd rect
			(at -1.905 -2.54 180)
			(size 0.635 1.651)
			(layers "F.Cu" "F.Mask" "F.Paste")
			(net "P5V_A_1")
		)
	)
)
